(kicad_pcb
	(version 20260206)
	(generator "pcbnew")
	(generator_version "10.0")
	(general
		(thickness 1.6)
		(legacy_teardrops no)
	)
	(paper "A4")
	(title_block
		(title "Bryce Canyon_IOM_M2_16342-2_OCP.brd")
		(comment 1 "Bryce Canyon / footprints 616-623 of 1146")
	)
	(layers
		(0 "F.Cu" signal "TOP")
		(4 "In1.Cu" signal "L2GND")
		(6 "In2.Cu" signal "L3")
		(8 "In3.Cu" signal "L4VCC")
		(10 "In4.Cu" signal "L5VCC")
		(12 "In5.Cu" signal "L6")
		(14 "In6.Cu" signal "L7GND")
		(2 "B.Cu" signal "BOTTOM")
		(9 "F.Adhes" user "F.Adhesive")
		(11 "B.Adhes" user "B.Adhesive")
		(13 "F.Paste" user "Package Geometry/Pastemask Top")
		(15 "B.Paste" user "Package Geometry/Pastemask Bottom")
		(5 "F.SilkS" user "Ref Des/Silkscreen Top")
		(7 "B.SilkS" user "Ref Des/Silkscreen Bottom")
		(1 "F.Mask" user "Board Geometry/Soldermask Top")
		(3 "B.Mask" user "Board Geometry/Soldermask Bottom")
		(17 "Dwgs.User" user "User.Drawings")
		(19 "Cmts.User" user "User.Comments")
		(21 "Eco1.User" user "User.Eco1")
		(23 "Eco2.User" user "User.Eco2")
		(25 "Edge.Cuts" user "Board Geometry/Outline")
		(27 "Margin" user)
		(31 "F.CrtYd" user "Package Geometry/Place Bound Top")
		(29 "B.CrtYd" user "Package Geometry/Place Bound Bottom")
		(35 "F.Fab" user "Ref Des/Assembly Top")
		(33 "B.Fab" user "Ref Des/Assembly Bottom")
	)
	(footprint ""
		(layer "F.Cu")
		(at 139.954 -15.5448 90)
		(property "Reference" "C138"
			(at 0 0 90)
			(layer "F.SilkS")
			(hide yes)
			(effects
				(font
					(size 1.27 1.27)
				)
			)
		)
		(property "Value" "SCD1U25V2KX-2-GP"
			(at 1.1811 -2.7051 90)
			(unlocked yes)
			(layer "F.Fab")
			(hide yes)
			(effects
				(font
					(size 1.016 1.016)
					(thickness 0.1524)
				)
			)
		)
		(property "Device Type" "C402H22"
			(at 1.1811 -4.2291 90)
			(unlocked yes)
			(layer "F.Fab")
			(hide yes)
			(effects
				(font
					(size 1.016 1.016)
					(thickness 0.1524)
				)
			)
		)
		(duplicate_pad_numbers_are_jumpers no)
		(fp_rect
			(start -0.4318 0.9525)
			(end 0.4318 -0.9525)
			(stroke
				(width 0)
				(type default)
			)
			(fill no)
			(layer "F.CrtYd")
		)
		(fp_rect
			(start -0.4318 0.9525)
			(end 0.4318 -0.9525)
			(stroke
				(width 0)
				(type default)
			)
			(fill no)
			(layer "F.Fab")
		)
		(pad "1" smd custom
			(at 0 -0.4445 90)
			(size 0.1524 0.1524)
			(layers "F.Cu" "F.Mask" "F.Paste")
			(net "P12V_IOM")
			(options
				(clearance outline)
				(anchor circle)
			)
			(primitives
				(gr_poly
					(pts
						(arc
							(start 0.3048 -0.2032)
							(mid 0.275042 -0.275042)
							(end 0.2032 -0.3048)
						)
						(arc
							(start -0.2032 -0.3048)
							(mid -0.275042 -0.275042)
							(end -0.3048 -0.2032)
						)
						(arc
							(start -0.3048 0.2032)
							(mid -0.275042 0.275042)
							(end -0.2032 0.3048)
						)
						(arc
							(start 0.2032 0.3048)
							(mid 0.275042 0.275042)
							(end 0.3048 0.2032)
						)
					)
					(width 0)
					(fill yes)
				)
			)
		)
		(pad "2" smd custom
			(at 0 0.4445 90)
			(size 0.1524 0.1524)
			(layers "F.Cu" "F.Mask" "F.Paste")
			(net "GND")
			(options
				(clearance outline)
				(anchor circle)
			)
			(primitives
				(gr_poly
					(pts
						(arc
							(start 0.3048 -0.2032)
							(mid 0.275042 -0.275042)
							(end 0.2032 -0.3048)
						)
						(arc
							(start -0.2032 -0.3048)
							(mid -0.275042 -0.275042)
							(end -0.3048 -0.2032)
						)
						(arc
							(start -0.3048 0.2032)
							(mid -0.275042 0.275042)
							(end -0.2032 0.3048)
						)
						(arc
							(start 0.2032 0.3048)
							(mid 0.275042 0.275042)
							(end 0.3048 0.2032)
						)
					)
					(width 0)
					(fill yes)
				)
			)
		)
	)
	(footprint ""
		(layer "F.Cu")
		(at 157.555184 -14.005052 -90)
		(property "Reference" "R517"
			(at 0 0 270)
			(layer "F.SilkS")
			(hide yes)
			(effects
				(font
					(size 1.27 1.27)
				)
			)
		)
		(property "Value" "0R2J-2-GP"
			(at 0.064008 -3.993896 270)
			(unlocked yes)
			(layer "F.Fab")
			(hide yes)
			(effects
				(font
					(size 1.016 1.016)
					(thickness 0.1524)
				)
			)
		)
		(property "Device Type" "R402H16"
			(at 0.064008 -5.517896 270)
			(unlocked yes)
			(layer "F.Fab")
			(hide yes)
			(effects
				(font
					(size 1.016 1.016)
					(thickness 0.1524)
				)
			)
		)
		(duplicate_pad_numbers_are_jumpers no)
		(fp_line
			(start -0.508 -0.9398)
			(end -0.508 0.9398)
			(stroke
				(width 0.1524)
				(type default)
			)
			(layer "F.SilkS")
		)
		(fp_line
			(start 0.508 -0.9398)
			(end -0.508 -0.9398)
			(stroke
				(width 0.1524)
				(type default)
			)
			(layer "F.SilkS")
		)
		(fp_rect
			(start -0.508 0.9398)
			(end 0.508 -0.9398)
			(stroke
				(width 0)
				(type default)
			)
			(fill no)
			(layer "F.CrtYd")
		)
		(fp_rect
			(start -0.508 0.9398)
			(end 0.508 -0.9398)
			(stroke
				(width 0)
				(type default)
			)
			(fill no)
			(layer "F.Fab")
		)
		(pad "1" smd custom
			(at 0 -0.4445 270)
			(size 0.1397 0.1397)
			(layers "F.Cu" "F.Mask" "F.Paste")
			(net "P1V8_STBY_VBST_RR")
			(options
				(clearance outline)
				(anchor circle)
			)
			(primitives
				(gr_poly
					(pts
						(arc
							(start -0.1778 -0.2794)
							(mid -0.249642 -0.249642)
							(end -0.2794 -0.1778)
						)
						(arc
							(start -0.2794 0.1778)
							(mid -0.249642 0.249642)
							(end -0.1778 0.2794)
						)
						(arc
							(start 0.1778 0.2794)
							(mid 0.249642 0.249642)
							(end 0.2794 0.1778)
						)
						(arc
							(start 0.2794 -0.1778)
							(mid 0.249642 -0.249642)
							(end 0.1778 -0.2794)
						)
					)
					(width 0)
					(fill yes)
				)
			)
		)
		(pad "2" smd custom
			(at 0 0.4445 270)
			(size 0.1397 0.1397)
			(layers "F.Cu" "F.Mask" "F.Paste")
			(net "P1V8_STBY_VBST")
			(options
				(clearance outline)
				(anchor circle)
			)
			(primitives
				(gr_poly
					(pts
						(arc
							(start -0.1778 -0.2794)
							(mid -0.249642 -0.249642)
							(end -0.2794 -0.1778)
						)
						(arc
							(start -0.2794 0.1778)
							(mid -0.249642 0.249642)
							(end -0.1778 0.2794)
						)
						(arc
							(start 0.1778 0.2794)
							(mid 0.249642 0.249642)
							(end 0.2794 0.1778)
						)
						(arc
							(start 0.2794 -0.1778)
							(mid 0.249642 -0.249642)
							(end 0.1778 -0.2794)
						)
					)
					(width 0)
					(fill yes)
				)
			)
		)
	)
	(footprint ""
		(layer "F.Cu")
		(at 57.9628 -162.7886 180)
		(property "Reference" "C120"
			(at 0 0 180)
			(layer "F.SilkS")
			(hide yes)
			(effects
				(font
					(size 1.27 1.27)
				)
			)
		)
		(property "Value" "SCD1U25V2KX-2-GP"
			(at 1.1811 -2.7051 180)
			(unlocked yes)
			(layer "F.Fab")
			(hide yes)
			(effects
				(font
					(size 1.016 1.016)
					(thickness 0.1524)
				)
			)
		)
		(property "Device Type" "C402H22"
			(at 1.1811 -4.2291 180)
			(unlocked yes)
			(layer "F.Fab")
			(hide yes)
			(effects
				(font
					(size 1.016 1.016)
					(thickness 0.1524)
				)
			)
		)
		(duplicate_pad_numbers_are_jumpers no)
		(fp_rect
			(start -0.4318 0.9525)
			(end 0.4318 -0.9525)
			(stroke
				(width 0)
				(type default)
			)
			(fill no)
			(layer "F.CrtYd")
		)
		(fp_rect
			(start -0.4318 0.9525)
			(end 0.4318 -0.9525)
			(stroke
				(width 0)
				(type default)
			)
			(fill no)
			(layer "F.Fab")
		)
		(pad "1" smd custom
			(at 0 -0.4445 180)
			(size 0.1524 0.1524)
			(layers "F.Cu" "F.Mask" "F.Paste")
			(net "ADC_P3V3_STBY")
			(options
				(clearance outline)
				(anchor circle)
			)
			(primitives
				(gr_poly
					(pts
						(arc
							(start 0.3048 -0.2032)
							(mid 0.275042 -0.275042)
							(end 0.2032 -0.3048)
						)
						(arc
							(start -0.2032 -0.3048)
							(mid -0.275042 -0.275042)
							(end -0.3048 -0.2032)
						)
						(arc
							(start -0.3048 0.2032)
							(mid -0.275042 0.275042)
							(end -0.2032 0.3048)
						)
						(arc
							(start 0.2032 0.3048)
							(mid 0.275042 0.275042)
							(end 0.3048 0.2032)
						)
					)
					(width 0)
					(fill yes)
				)
			)
		)
		(pad "2" smd custom
			(at 0 0.4445 180)
			(size 0.1524 0.1524)
			(layers "F.Cu" "F.Mask" "F.Paste")
			(net "GND")
			(options
				(clearance outline)
				(anchor circle)
			)
			(primitives
				(gr_poly
					(pts
						(arc
							(start 0.3048 -0.2032)
							(mid 0.275042 -0.275042)
							(end 0.2032 -0.3048)
						)
						(arc
							(start -0.2032 -0.3048)
							(mid -0.275042 -0.275042)
							(end -0.3048 -0.2032)
						)
						(arc
							(start -0.3048 0.2032)
							(mid -0.275042 0.275042)
							(end -0.2032 0.3048)
						)
						(arc
							(start 0.2032 0.3048)
							(mid 0.275042 0.275042)
							(end 0.3048 0.2032)
						)
					)
					(width 0)
					(fill yes)
				)
			)
		)
	)
	(footprint ""
		(layer "F.Cu")
		(at 79.72298 -178.555396 180)
		(property "Reference" "C193"
			(at 0 0 180)
			(layer "F.SilkS")
			(hide yes)
			(effects
				(font
					(size 1.27 1.27)
				)
			)
		)
		(property "Value" "SC10U6D3V5KX-4GP"
			(at -0.0762 -6.1214 180)
			(unlocked yes)
			(layer "F.Fab")
			(hide yes)
			(effects
				(font
					(size 1.016 1.016)
					(thickness 0.1524)
				)
			)
		)
		(property "Device Type" "C805H58"
			(at -0.0762 -8.1534 180)
			(unlocked yes)
			(layer "F.Fab")
			(hide yes)
			(effects
				(font
					(size 1.016 1.016)
					(thickness 0.1524)
				)
			)
		)
		(duplicate_pad_numbers_are_jumpers no)
		(fp_line
			(start 0.635 0)
			(end -0.635 0)
			(stroke
				(width 0.508)
				(type default)
			)
			(layer "F.SilkS")
		)
		(fp_rect
			(start -0.9652 1.778)
			(end 0.9652 -1.778)
			(stroke
				(width 0)
				(type default)
			)
			(fill no)
			(layer "F.CrtYd")
		)
		(fp_poly
			(pts
				(xy -0.9652 -1.778) (xy 0.9652 -1.778) (xy 0.9652 1.778) (xy -0.9652 1.778)
			)
			(stroke
				(width 0)
				(type default)
			)
			(fill no)
			(layer "F.Fab")
		)
		(pad "1" smd rect
			(at 0 -0.9652 180)
			(size 1.397 1.143)
			(layers "F.Cu" "F.Mask" "F.Paste")
			(net "TPS74801_P2V5_STBY_OUT")
		)
		(pad "2" smd rect
			(at 0 0.9652 180)
			(size 1.397 1.143)
			(layers "F.Cu" "F.Mask" "F.Paste")
			(net "GND")
		)
	)
	(footprint ""
		(layer "F.Cu")
		(at 82.441796 -173.80458 90)
		(property "Reference" "C194"
			(at 0 0 90)
			(layer "F.SilkS")
			(hide yes)
			(effects
				(font
					(size 1.27 1.27)
				)
			)
		)
		(property "Value" "SC10U6D3V5KX-4GP"
			(at -0.0762 -6.1214 90)
			(unlocked yes)
			(layer "F.Fab")
			(hide yes)
			(effects
				(font
					(size 1.016 1.016)
					(thickness 0.1524)
				)
			)
		)
		(property "Device Type" "C805H58"
			(at -0.0762 -8.1534 90)
			(unlocked yes)
			(layer "F.Fab")
			(hide yes)
			(effects
				(font
					(size 1.016 1.016)
					(thickness 0.1524)
				)
			)
		)
		(duplicate_pad_numbers_are_jumpers no)
		(fp_line
			(start 0.635 0)
			(end -0.635 0)
			(stroke
				(width 0.508)
				(type default)
			)
			(layer "F.SilkS")
		)
		(fp_rect
			(start -0.9652 1.778)
			(end 0.9652 -1.778)
			(stroke
				(width 0)
				(type default)
			)
			(fill no)
			(layer "F.CrtYd")
		)
		(fp_poly
			(pts
				(xy -0.9652 -1.778) (xy 0.9652 -1.778) (xy 0.9652 1.778) (xy -0.9652 1.778)
			)
			(stroke
				(width 0)
				(type default)
			)
			(fill no)
			(layer "F.Fab")
		)
		(pad "1" smd rect
			(at 0 -0.9652 90)
			(size 1.397 1.143)
			(layers "F.Cu" "F.Mask" "F.Paste")
			(net "TPS74801_P2V5_STBY_OUT")
		)
		(pad "2" smd rect
			(at 0 0.9652 90)
			(size 1.397 1.143)
			(layers "F.Cu" "F.Mask" "F.Paste")
			(net "GND")
		)
	)
	(footprint ""
		(layer "F.Cu")
		(at 33.5026 -159.2834)
		(property "Reference" "C90"
			(at 0 0 0)
			(layer "F.SilkS")
			(hide yes)
			(effects
				(font
					(size 1.27 1.27)
				)
			)
		)
		(property "Value" "SC1U16V3KX-5GP"
			(at 0 -2.8194 0)
			(unlocked yes)
			(layer "F.Fab")
			(hide yes)
			(effects
				(font
					(size 1.016 1.016)
					(thickness 0.1524)
				)
			)
		)
		(property "Device Type" "C603H36"
			(at 0 -4.3434 0)
			(unlocked yes)
			(layer "F.Fab")
			(hide yes)
			(effects
				(font
					(size 1.016 1.016)
					(thickness 0.1524)
				)
			)
		)
		(duplicate_pad_numbers_are_jumpers no)
		(fp_line
			(start 0.508 0)
			(end -0.508 0)
			(stroke
				(width 0.2032)
				(type default)
			)
			(layer "F.SilkS")
		)
		(fp_rect
			(start -0.5842 1.3335)
			(end 0.5842 -1.3335)
			(stroke
				(width 0)
				(type default)
			)
			(fill no)
			(layer "F.CrtYd")
		)
		(fp_rect
			(start -0.5842 1.3335)
			(end 0.5842 -1.3335)
			(stroke
				(width 0)
				(type default)
			)
			(fill no)
			(layer "F.Fab")
		)
		(pad "1" smd custom
			(at 0 -0.762)
			(size 0.2159 0.2159)
			(layers "F.Cu" "F.Mask" "F.Paste")
			(net "DACAV33")
			(options
				(clearance outline)
				(anchor circle)
			)
			(primitives
				(gr_poly
					(pts
						(arc
							(start -0.3302 -0.4318)
							(mid -0.402042 -0.402042)
							(end -0.4318 -0.3302)
						)
						(arc
							(start -0.4318 0.3302)
							(mid -0.402042 0.402042)
							(end -0.3302 0.4318)
						)
						(arc
							(start 0.3302 0.4318)
							(mid 0.402042 0.402042)
							(end 0.4318 0.3302)
						)
						(arc
							(start 0.4318 -0.3302)
							(mid 0.402042 -0.402042)
							(end 0.3302 -0.4318)
						)
					)
					(width 0)
					(fill yes)
				)
			)
		)
		(pad "2" smd custom
			(at 0 0.762)
			(size 0.2159 0.2159)
			(layers "F.Cu" "F.Mask" "F.Paste")
			(net "GND")
			(options
				(clearance outline)
				(anchor circle)
			)
			(primitives
				(gr_poly
					(pts
						(arc
							(start -0.3302 -0.4318)
							(mid -0.402042 -0.402042)
							(end -0.4318 -0.3302)
						)
						(arc
							(start -0.4318 0.3302)
							(mid -0.402042 0.402042)
							(end -0.3302 0.4318)
						)
						(arc
							(start 0.3302 0.4318)
							(mid 0.402042 0.402042)
							(end 0.4318 0.3302)
						)
						(arc
							(start 0.4318 -0.3302)
							(mid 0.402042 -0.402042)
							(end 0.3302 -0.4318)
						)
					)
					(width 0)
					(fill yes)
				)
			)
		)
	)
	(footprint ""
		(layer "F.Cu")
		(at 43.27652 -131.7498 180)
		(property "Reference" "R262"
			(at 0 0 180)
			(layer "F.SilkS")
			(hide yes)
			(effects
				(font
					(size 1.27 1.27)
				)
			)
		)
		(property "Value" "4K7R2F-GP"
			(at 0.064008 -3.993896 180)
			(unlocked yes)
			(layer "F.Fab")
			(hide yes)
			(effects
				(font
					(size 1.016 1.016)
					(thickness 0.1524)
				)
			)
		)
		(property "Device Type" "R402H16"
			(at 0.064008 -5.517896 180)
			(unlocked yes)
			(layer "F.Fab")
			(hide yes)
			(effects
				(font
					(size 1.016 1.016)
					(thickness 0.1524)
				)
			)
		)
		(duplicate_pad_numbers_are_jumpers no)
		(fp_line
			(start 0.508 -0.9398)
			(end -0.508 -0.9398)
			(stroke
				(width 0.1524)
				(type default)
			)
			(layer "F.SilkS")
		)
		(fp_line
			(start -0.508 -0.9398)
			(end -0.508 0.9398)
			(stroke
				(width 0.1524)
				(type default)
			)
			(layer "F.SilkS")
		)
		(fp_rect
			(start -0.508 0.9398)
			(end 0.508 -0.9398)
			(stroke
				(width 0)
				(type default)
			)
			(fill no)
			(layer "F.CrtYd")
		)
		(fp_rect
			(start -0.508 0.9398)
			(end 0.508 -0.9398)
			(stroke
				(width 0)
				(type default)
			)
			(fill no)
			(layer "F.Fab")
		)
		(pad "1" smd custom
			(at 0 -0.4445 180)
			(size 0.1397 0.1397)
			(layers "F.Cu" "F.Mask" "F.Paste")
			(net "P3V3_STBY")
			(options
				(clearance outline)
				(anchor circle)
			)
			(primitives
				(gr_poly
					(pts
						(arc
							(start -0.1778 -0.2794)
							(mid -0.249642 -0.249642)
							(end -0.2794 -0.1778)
						)
						(arc
							(start -0.2794 0.1778)
							(mid -0.249642 0.249642)
							(end -0.1778 0.2794)
						)
						(arc
							(start 0.1778 0.2794)
							(mid 0.249642 0.249642)
							(end 0.2794 0.1778)
						)
						(arc
							(start 0.2794 -0.1778)
							(mid 0.249642 -0.249642)
							(end 0.1778 -0.2794)
						)
					)
					(width 0)
					(fill yes)
				)
			)
		)
		(pad "2" smd custom
			(at 0 0.4445 180)
			(size 0.1397 0.1397)
			(layers "F.Cu" "F.Mask" "F.Paste")
			(net "BMC_GPIOY0")
			(options
				(clearance outline)
				(anchor circle)
			)
			(primitives
				(gr_poly
					(pts
						(arc
							(start -0.1778 -0.2794)
							(mid -0.249642 -0.249642)
							(end -0.2794 -0.1778)
						)
						(arc
							(start -0.2794 0.1778)
							(mid -0.249642 0.249642)
							(end -0.1778 0.2794)
						)
						(arc
							(start 0.1778 0.2794)
							(mid 0.249642 0.249642)
							(end 0.2794 0.1778)
						)
						(arc
							(start 0.2794 -0.1778)
							(mid 0.249642 -0.249642)
							(end 0.1778 -0.2794)
						)
					)
					(width 0)
					(fill yes)
				)
			)
		)
	)
	(footprint ""
		(layer "F.Cu")
		(at 198.12 -140.97 -135)
		(property "Reference" "VIA55"
			(at 0 0 225)
			(layer "F.SilkS")
			(hide yes)
			(effects
				(font
					(size 1.27 1.27)
				)
			)
		)
		(property "Value" "85OHM-8L-1D6MM-L16L18-GP"
			(at 4.064105 0.609655 225)
			(unlocked yes)
			(layer "F.Fab")
			(hide yes)
			(effects
				(font
					(size 1.016 1.016)
					(thickness 0.1524)
				)
			)
		)
		(property "Device Type" "VIA-PCIE-4P-368076"
			(at 4.064105 -0.914474 225)
			(unlocked yes)
			(layer "F.Fab")
			(hide yes)
			(effects
				(font
					(size 1.016 1.016)
					(thickness 0.1524)
				)
			)
		)
		(duplicate_pad_numbers_are_jumpers no)
		(fp_poly
			(pts
				(xy -1.841491 -0.381057) (xy 1.841509 -0.381058) (xy 1.841508 0.380942) (xy -1.841491 0.380942)
			)
			(stroke
				(width 0)
				(type default)
			)
			(fill no)
			(layer "F.CrtYd")
		)
		(fp_poly
			(pts
				(xy -1.841491 -0.381057) (xy 1.841509 -0.381058) (xy 1.841508 0.380942) (xy -1.841491 0.380942)
			)
			(stroke
				(width 0)
				(type default)
			)
			(fill no)
			(layer "F.Fab")
		)
		(pad "1" thru_hole circle
			(at -1.460499 0 225)
			(size 0.508 0.508)
			(drill 0.254)
			(layers "*.Cu" "*.Mask")
			(remove_unused_layers no)
			(net "GND")
			(clearance 0.127)
			(thermal_gap 0.127)
		)
		(pad "2" thru_hole circle
			(at -0.4445 0 225)
			(size 0.508 0.508)
			(drill 0.254)
			(layers "*.Cu" "*.Mask")
			(remove_unused_layers no)
			(net "PCIE_IOM_TO_COMP_10_DP")
			(clearance 0.127)
			(thermal_gap 0.127)
		)
		(pad "3" thru_hole circle
			(at 0.4445 0 225)
			(size 0.508 0.508)
			(drill 0.254)
			(layers "*.Cu" "*.Mask")
			(remove_unused_layers no)
			(net "PCIE_IOM_TO_COMP_10_DN")
			(clearance 0.127)
			(thermal_gap 0.127)
		)
		(pad "4" thru_hole circle
			(at 1.460499 0 225)
			(size 0.508 0.508)
			(drill 0.254)
			(layers "*.Cu" "*.Mask")
			(remove_unused_layers no)
			(net "GND")
			(clearance 0.127)
			(thermal_gap 0.127)
		)
	)
)
